# BASEBOARD_FAB2 (Tioga Pass) — schematic netlist excerpt (pin names and nets, part order shuffled) for the footprints in the layout excerpt that follows; sources: Cadence DE-HDL packaged netlist, KiCad conversion of Wiwynn_Tioga_Pass_MB.brd

C1M17  CAP  0.22UF 16V 10% X7R  pkg 0402  page 106 : A = P3E_CPU0_PE3_OCP_TXN<10> ; B = P3E_OCP_CPU0_PE3_C_TXN<10>
R4U1  RES  4.75K 1% CHIP  pkg 0402  page 94 : A = P3V3_STBY ; B = FM_MEM_THERM_EVENT_LVT3_N
FB3M2  FERRITE  120 FB  pkg SM  page 127 : A = P1V05_PCH_STBY ; B = P1V05_PCH_STBY_VCCA_PLL0

(kicad_pcb
	(version 20260206)
	(generator "pcbnew")
	(generator_version "10.0")
	(general
		(thickness 1.6)
		(legacy_teardrops no)
	)
	(paper "A4")
	(title_block
		(title "Wiwynn_Tioga_Pass_MB.brd")
		(comment 1 "Tioga Pass / footprints 2682-2684 of 4770")
	)
	(layers
		(0 "F.Cu" signal "TOP")
		(4 "In1.Cu" signal "L2GND")
		(6 "In2.Cu" signal "L3")
		(8 "In3.Cu" signal "L4GND")
		(10 "In4.Cu" signal "L5")
		(12 "In5.Cu" signal "L6GND")
		(14 "In6.Cu" signal "L7VCC")
		(16 "In7.Cu" signal "L8VCC")
		(18 "In8.Cu" signal "L9GND")
		(20 "In9.Cu" signal "L10")
		(22 "In10.Cu" signal "L11GND")
		(24 "In11.Cu" signal "L12")
		(26 "In12.Cu" signal "L13GND")
		(2 "B.Cu" signal "BOTTOM")
		(9 "F.Adhes" user "F.Adhesive")
		(11 "B.Adhes" user "B.Adhesive")
		(13 "F.Paste" user "Package Geometry/Pastemask Top")
		(15 "B.Paste" user "Package Geometry/Pastemask Bottom")
		(5 "F.SilkS" user "Ref Des/Silkscreen Top")
		(7 "B.SilkS" user "Ref Des/Silkscreen Bottom")
		(1 "F.Mask" user "Board Geometry/Soldermask Top")
		(3 "B.Mask" user "Board Geometry/Soldermask Bottom")
		(17 "Dwgs.User" user "User.Drawings")
		(19 "Cmts.User" user "User.Comments")
		(21 "Eco1.User" user "User.Eco1")
		(23 "Eco2.User" user "User.Eco2")
		(25 "Edge.Cuts" user "Board Geometry/Outline")
		(27 "Margin" user)
		(31 "F.CrtYd" user "Package Geometry/Place Bound Top")
		(29 "B.CrtYd" user "Package Geometry/Place Bound Bottom")
		(35 "F.Fab" user "Ref Des/Assembly Top")
		(33 "B.Fab" user "Ref Des/Assembly Bottom")
	)
	(footprint ""
		(layer "B.Cu")
		(at 372.11 -135.1661 -90)
		(property "Reference" "FB3M2"
			(at 0 0 90)
			(layer "B.SilkS")
			(hide yes)
			(effects
				(font
					(size 1.27 1.27)
				)
				(justify mirror)
			)
		)
		(property "Value" ""
			(at 0 0 90)
			(layer "B.Fab")
			(effects
				(font
					(size 1.27 1.27)
				)
				(justify mirror)
			)
		)
		(duplicate_pad_numbers_are_jumpers no)
		(fp_poly
			(pts
				(xy 0.15113 -0.47498) (xy -1.59893 -0.47498) (xy -1.59893 0.47498) (xy 0.15113 0.47498)
			)
			(stroke
				(width 0)
				(type default)
			)
			(fill no)
			(layer "B.CrtYd")
		)
		(fp_line
			(start -1.59893 0.47498)
			(end 0.15113 0.47498)
			(stroke
				(width 0.1)
				(type default)
			)
			(layer "B.Fab")
		)
		(fp_line
			(start 0.15113 0.47498)
			(end 0.15113 -0.47498)
			(stroke
				(width 0.1)
				(type default)
			)
			(layer "B.Fab")
		)
		(fp_line
			(start -1.59893 -0.47498)
			(end -1.59893 0.47498)
			(stroke
				(width 0.1)
				(type default)
			)
			(layer "B.Fab")
		)
		(fp_line
			(start 0.15113 -0.47498)
			(end -1.59893 -0.47498)
			(stroke
				(width 0.1)
				(type default)
			)
			(layer "B.Fab")
		)
		(pad "1" smd rect
			(at 0 0 90)
			(size 0.9398 0.9398)
			(layers "B.Cu" "B.Mask" "B.Paste")
			(net "P1V05_PCH_STBY")
		)
		(pad "2" smd rect
			(at -1.4478 0 90)
			(size 0.9398 0.9398)
			(layers "B.Cu" "B.Mask" "B.Paste")
			(net "P1V05_PCH_STBY_VCCA_PLL0")
		)
		(zone
			(layer "B.Cu")
			(hatch none 0.5)
			(connect_pads
				(clearance 0)
			)
			(min_thickness 0.25)
			(keepout
				(tracks allowed)
				(vias not_allowed)
				(pads allowed)
				(copperpour not_allowed)
				(footprints allowed)
			)
			(placement
				(enabled no)
				(sheetname "")
			)
			(fill
				(thermal_gap 0.5)
				(thermal_bridge_width 0.5)
				(island_removal_mode 0)
			)
			(polygon
				(pts
					(xy 371.6401 -135.636) (xy 372.5799 -135.636) (xy 372.5799 -136.144) (xy 371.6401 -136.144)
				)
			)
		)
		(zone
			(layer "B.Cu")
			(hatch none 0.5)
			(connect_pads
				(clearance 0)
			)
			(min_thickness 0.25)
			(keepout
				(tracks not_allowed)
				(vias allowed)
				(pads allowed)
				(copperpour not_allowed)
				(footprints allowed)
			)
			(placement
				(enabled no)
				(sheetname "")
			)
			(fill
				(thermal_gap 0.5)
				(thermal_bridge_width 0.5)
				(island_removal_mode 0)
			)
			(polygon
				(pts
					(xy 371.6401 -135.636) (xy 372.5799 -135.636) (xy 372.5799 -136.144) (xy 371.6401 -136.144)
				)
			)
		)
	)
	(footprint ""
		(layer "B.Cu")
		(at 331.343 -11.7094)
		(property "Reference" "R4U1"
			(at 0 0 0)
			(layer "B.SilkS")
			(hide yes)
			(effects
				(font
					(size 1.27 1.27)
				)
				(justify mirror)
			)
		)
		(property "Value" ""
			(at 0 0 0)
			(layer "B.Fab")
			(effects
				(font
					(size 1.27 1.27)
				)
				(justify mirror)
			)
		)
		(duplicate_pad_numbers_are_jumpers no)
		(fp_poly
			(pts
				(xy 0.2794 -0.1016) (xy -0.2794 -0.1016) (xy -0.2794 0.9906) (xy 0.2794 0.9906)
			)
			(stroke
				(width 0)
				(type default)
			)
			(fill no)
			(layer "B.CrtYd")
		)
		(fp_line
			(start -0.2794 -0.1016)
			(end 0.2794 -0.1016)
			(stroke
				(width 0.1)
				(type default)
			)
			(layer "B.Fab")
		)
		(fp_line
			(start -0.2794 0.9906)
			(end -0.2794 -0.1016)
			(stroke
				(width 0.1)
				(type default)
			)
			(layer "B.Fab")
		)
		(fp_line
			(start 0.2794 -0.1016)
			(end 0.2794 0.9906)
			(stroke
				(width 0.1)
				(type default)
			)
			(layer "B.Fab")
		)
		(fp_line
			(start 0.2794 0.9906)
			(end -0.2794 0.9906)
			(stroke
				(width 0.1)
				(type default)
			)
			(layer "B.Fab")
		)
		(pad "1" smd rect
			(at 0 0 180)
			(size 0.508 0.508)
			(layers "B.Cu" "B.Mask" "B.Paste")
			(net "P3V3_STBY")
		)
		(pad "2" smd rect
			(at 0 0.889 180)
			(size 0.508 0.508)
			(layers "B.Cu" "B.Mask" "B.Paste")
			(net "FM_MEM_THERM_EVENT_LVT3_N")
		)
		(zone
			(layer "B.Cu")
			(hatch none 0.5)
			(connect_pads
				(clearance 0)
			)
			(min_thickness 0.25)
			(keepout
				(tracks allowed)
				(vias not_allowed)
				(pads allowed)
				(copperpour not_allowed)
				(footprints allowed)
			)
			(placement
				(enabled no)
				(sheetname "")
			)
			(fill
				(thermal_gap 0.5)
				(thermal_bridge_width 0.5)
				(island_removal_mode 0)
			)
			(polygon
				(pts
					(xy 331.597 -11.4554) (xy 331.089 -11.4554) (xy 331.089 -11.0744) (xy 331.597 -11.0744)
				)
			)
		)
		(zone
			(layer "B.Cu")
			(hatch none 0.5)
			(connect_pads
				(clearance 0)
			)
			(min_thickness 0.25)
			(keepout
				(tracks not_allowed)
				(vias allowed)
				(pads allowed)
				(copperpour not_allowed)
				(footprints allowed)
			)
			(placement
				(enabled no)
				(sheetname "")
			)
			(fill
				(thermal_gap 0.5)
				(thermal_bridge_width 0.5)
				(island_removal_mode 0)
			)
			(polygon
				(pts
					(xy 331.597 -11.0744) (xy 331.089 -11.0744) (xy 331.089 -11.4554) (xy 331.597 -11.4554)
				)
			)
		)
	)
	(footprint ""
		(layer "B.Cu")
		(at 449.199 -116.49202)
		(property "Reference" "C1M17"
			(at 0 0 0)
			(layer "B.SilkS")
			(hide yes)
			(effects
				(font
					(size 1.27 1.27)
				)
				(justify mirror)
			)
		)
		(property "Value" ""
			(at 0 0 0)
			(layer "B.Fab")
			(effects
				(font
					(size 1.27 1.27)
				)
				(justify mirror)
			)
		)
		(duplicate_pad_numbers_are_jumpers no)
		(fp_rect
			(start -0.3048 0.9906)
			(end 0.3048 -0.1016)
			(stroke
				(width 0)
				(type default)
			)
			(fill no)
			(layer "B.CrtYd")
		)
		(fp_line
			(start -0.3048 -0.1016)
			(end 0.3048 -0.1016)
			(stroke
				(width 0.1)
				(type default)
			)
			(layer "B.Fab")
		)
		(fp_line
			(start -0.3048 0.9906)
			(end -0.3048 -0.1016)
			(stroke
				(width 0.1)
				(type default)
			)
			(layer "B.Fab")
		)
		(fp_line
			(start 0.3048 -0.1016)
			(end 0.3048 0.9906)
			(stroke
				(width 0.1)
				(type default)
			)
			(layer "B.Fab")
		)
		(fp_line
			(start 0.3048 0.9906)
			(end -0.3048 0.9906)
			(stroke
				(width 0.1)
				(type default)
			)
			(layer "B.Fab")
		)
		(pad "1" smd rect
			(at 0 0 180)
			(size 0.508 0.508)
			(layers "B.Cu" "B.Mask" "B.Paste")
			(net "P3E_CPU0_PE3_OCP_TXN<10>")
		)
		(pad "2" smd rect
			(at 0 0.889 180)
			(size 0.508 0.508)
			(layers "B.Cu" "B.Mask" "B.Paste")
			(net "P3E_OCP_CPU0_PE3_C_TXN<10>")
		)
		(zone
			(layer "B.Cu")
			(hatch none 0.5)
			(connect_pads
				(clearance 0)
			)
			(min_thickness 0.25)
			(keepout
				(tracks allowed)
				(vias not_allowed)
				(pads allowed)
				(copperpour not_allowed)
				(footprints allowed)
			)
			(placement
				(enabled no)
				(sheetname "")
			)
			(fill
				(thermal_gap 0.5)
				(thermal_bridge_width 0.5)
				(island_removal_mode 0)
			)
			(polygon
				(pts
					(xy 448.945 -115.85702) (xy 449.453 -115.85702) (xy 449.453 -116.23802) (xy 448.945 -116.23802)
				)
			)
		)
		(zone
			(layer "B.Cu")
			(hatch none 0.5)
			(connect_pads
				(clearance 0)
			)
			(min_thickness 0.25)
			(keepout
				(tracks not_allowed)
				(vias allowed)
				(pads allowed)
				(copperpour not_allowed)
				(footprints allowed)
			)
			(placement
				(enabled no)
				(sheetname "")
			)
			(fill
				(thermal_gap 0.5)
				(thermal_bridge_width 0.5)
				(island_removal_mode 0)
			)
			(polygon
				(pts
					(xy 448.945 -115.85702) (xy 449.453 -115.85702) (xy 449.453 -116.23802) (xy 448.945 -116.23802)
				)
			)
		)
	)
)
